FILE_TYPE = CONNECTIVITY;
{Allegro Design Entry HDL 17.2-2016 S081 (4005846) 1/11/2022}
"PAGE_NUMBER" = 320;
0"NC";
1"GND\g";
2"GND\g";
3"PRSNT_CABLE_GPU_A3_N";
4"GPU_FPGA_OVERT_N";
5"P5E_CPU0_PE0_RX_DN<9>";
6"P5E_CPU0_PE0_RX_DP<9>";
7"P5E_CPU0_PE4_RX_DP<6>";
8"P5E_CPU0_PE4_TX_C_DP<7>";
9"P5E_CPU0_PE4_TX_C_DP<6>";
10"P5E_CPU0_PE0_RX_DN<10>";
11"P5E_CPU0_PE0_RX_DP<10>";
12"P5E_CPU0_PE4_RX_DP<5>";
13"P5E_CPU0_PE4_RX_DN<5>";
14"P5E_CPU0_PE0_TX_C_DN<10>";
15"P5E_CPU0_PE0_TX_C_DP<10>";
16"P5E_CPU0_PE4_TX_C_DN<5>";
17"P5E_CPU0_PE4_TX_C_DP<5>";
18"NC_J108_N6";
19"P5E_CPU0_PE0_TX_C_DP<9>";
20"P5E_CPU0_PE4_RX_DN<6>";
21"P5E_CPU0_PE4_TX_C_DP<2>";
22"PRSNT_CABLE_GPU_A2_N";
23"NC_J108_N4";
24"P5E_CPU0_PE4_TX_C_DP<3>";
25"P5E_CPU0_PE0_RX_DN<13>";
26"P5E_CPU0_PE0_RX_DP<13>";
27"P5E_CPU0_PE4_RX_DN<2>";
28"P5E_CPU0_PE4_RX_DP<2>";
29"P5E_CPU0_PE0_TX_C_DP<13>";
30"P5E_CPU0_PE4_TX_C_DN<2>";
31"P5E_CPU0_PE0_RX_DN<14>";
32"P5E_CPU0_PE4_RX_DP<1>";
33"P5E_CPU0_PE0_TX_C_DP<14>";
34"P5E_CPU0_PE4_TX_C_DP<1>";
35"P5E_CPU0_PE0_TX_C_DN<13>";
36"P5E_CPU0_PE0_TX_C_DN<14>";
37"P5E_CPU0_PE4_RX_DN<1>";
38"P5E_CPU0_PE0_RX_DP<14>";
39"P5E_CPU0_PE4_TX_C_DN<1>";
40"NC_J108_N2";
41"P5E_CPU0_PE4_TX_C_DN<7>";
42"P5E_CPU0_PE0_TX_C_DP<8>";
43"P5E_CPU0_PE0_TX_C_DN<8>";
44"P5E_CPU0_PE0_RX_DP<8>";
45"P5E_CPU0_PE0_RX_DN<8>";
46"P5E_CPU0_PE4_TX_C_DP<4>";
47"P5E_CPU0_PE4_TX_C_DN<4>";
48"P5E_CPU0_PE4_TX_C_DN<6>";
49"P5E_CPU0_PE0_TX_C_DP<11>";
50"P5E_CPU0_PE0_TX_C_DN<11>";
51"P5E_CPU0_PE0_TX_C_DN<9>";
52"P5E_CPU0_PE4_RX_DP<4>";
53"P5E_CPU0_PE4_RX_DN<4>";
54"P5E_CPU0_PE4_RX_DN<7>";
55"P5E_CPU0_PE4_RX_DP<7>";
56"P5E_CPU0_PE0_RX_DN<11>";
57"P5E_CPU0_PE0_RX_DP<11>";
58"GPU_3V3IO_RSVD5_FFU";
59"GPU_3V3IO_RSVD3_FFU";
60"P5E_CPU0_PE4_TX_C_DN<3>";
61"P5E_CPU0_PE0_TX_C_DP<12>";
62"P5E_CPU0_PE0_RX_DN<15>";
63"P5E_CPU0_PE0_RX_DP<15>";
64"P5E_CPU0_PE4_RX_DN<0>";
65"P5E_CPU0_PE4_RX_DP<0>";
66"P5E_CPU0_PE0_TX_C_DN<15>";
67"P5E_CPU0_PE0_TX_C_DP<15>";
68"P5E_CPU0_PE4_TX_C_DN<0>";
69"P5E_CPU0_PE4_TX_C_DP<0>";
70"P5E_CPU0_PE0_TX_C_DN<12>";
71"P5E_CPU0_PE4_RX_DP<3>";
72"P5E_CPU0_PE4_RX_DN<3>";
73"P5E_CPU0_PE0_RX_DP<12>";
74"P5E_CPU0_PE0_RX_DN<12>";
%"UNIVERSAL_GND"
"1","(-2150,-1475)","0","logical_power","I19";
;
CDS_LIB"logical_power"
HDL_POWER"GND";
"A"2;
%"UNIVERSAL_GND"
"1","(2350,-1575)","0","logical_power","I56";
;
HDL_POWER"GND"
CDS_LIB"logical_power";
"A"1;
%"CONN112_10137002101LF"
"2","(3500,375)","0","pure_quanta","I57";
;
PART_NUMBER"DFHSB2FR012"
PART_TYPE"THLF"
MATERIAL"IO"
LOCATION"J108"
CDS_LMAN_SYM_OUTLINE"-775,1650,775,-1650"
NEEDS_NO_SIZE"TRUE"
CDS_LIB"pure_quanta"
VALUE"CONN112_10137002-101LF"
$SEC"2"
CDS_SEC"2";
"N4"
$PN"N4"23;
"M4"
$PN"M4"1;
"N3"
$PN"N3"1;
"M3"
$PN"M3"21;
"N2"
$PN"N2"40;
"M2"
$PN"M2"1;
"N1"
$PN"N1"1;
"M1"
$PN"M1"69;
"L1"
$PN"L1"68;
"L2"
$PN"L2"39;
"L3"
$PN"L3"30;
"L4"
$PN"L4"24;
"K1"
$PN"K1"1;
"K2"
$PN"K2"34;
"K3"
$PN"K3"1;
"K4"
$PN"K4"60;
"J1"
$PN"J1"67;
"J2"
$PN"J2"1;
"J3"
$PN"J3"29;
"J4"
$PN"J4"1;
"I1"
$PN"I1"66;
"I2"
$PN"I2"33;
"I3"
$PN"I3"35;
"I4"
$PN"I4"61;
"H1"
$PN"H1"1;
"H2"
$PN"H2"36;
"H3"
$PN"H3"1;
"H4"
$PN"H4"70;
"G1"
$PN"G1"65;
"G2"
$PN"G2"1;
"G3"
$PN"G3"28;
"G4"
$PN"G4"1;
"F1"
$PN"F1"64;
"F2"
$PN"F2"37;
"F3"
$PN"F3"27;
"F4"
$PN"F4"72;
"E1"
$PN"E1"1;
"E2"
$PN"E2"32;
"E3"
$PN"E3"1;
"E4"
$PN"E4"71;
"D1"
$PN"D1"63;
"D2"
$PN"D2"1;
"D3"
$PN"D3"26;
"D4"
$PN"D4"1;
"C1"
$PN"C1"62;
"C2"
$PN"C2"38;
"C3"
$PN"C3"25;
"C4"
$PN"C4"73;
"B1"
$PN"B1"1;
"B2"
$PN"B2"31;
"B3"
$PN"B3"1;
"B4"
$PN"B4"74;
"A1"
$PN"A1"59;
"A2"
$PN"A2"1;
"A3"
$PN"A3"22;
"A4"
$PN"A4"1;
%"CONN112_10137002101LF"
"1","(-1050,425)","0","pure_quanta","I76";
;
PART_NUMBER"DFHSB2FR012"
PART_TYPE"THLF"
MATERIAL"IO"
LOCATION"J108"
VALUE"CONN112_10137002-101LF"
CDS_LMAN_SYM_OUTLINE"-775,1650,775,-1650"
NEEDS_NO_SIZE"TRUE"
CDS_LIB"pure_quanta"
$SEC"1"
CDS_SEC"1";
"N8"
$PN"N8"3;
"M8"
$PN"M8"2;
"N7"
$PN"N7"2;
"M7"
$PN"M7"9;
"N6"
$PN"N6"18;
"M6"
$PN"M6"2;
"N5"
$PN"N5"2;
"M5"
$PN"M5"46;
"L5"
$PN"L5"47;
"L6"
$PN"L6"17;
"L7"
$PN"L7"48;
"L8"
$PN"L8"8;
"K5"
$PN"K5"2;
"K6"
$PN"K6"16;
"K7"
$PN"K7"2;
"K8"
$PN"K8"41;
"J5"
$PN"J5"49;
"J6"
$PN"J6"2;
"J7"
$PN"J7"19;
"J8"
$PN"J8"2;
"I5"
$PN"I5"50;
"I6"
$PN"I6"15;
"I7"
$PN"I7"51;
"I8"
$PN"I8"42;
"H5"
$PN"H5"2;
"H6"
$PN"H6"14;
"H7"
$PN"H7"2;
"H8"
$PN"H8"43;
"G5"
$PN"G5"52;
"G6"
$PN"G6"2;
"G7"
$PN"G7"7;
"G8"
$PN"G8"2;
"F5"
$PN"F5"53;
"F6"
$PN"F6"13;
"F7"
$PN"F7"20;
"F8"
$PN"F8"54;
"E5"
$PN"E5"2;
"E6"
$PN"E6"12;
"E7"
$PN"E7"2;
"E8"
$PN"E8"55;
"D5"
$PN"D5"56;
"D6"
$PN"D6"2;
"D7"
$PN"D7"6;
"D8"
$PN"D8"2;
"C5"
$PN"C5"57;
"C6"
$PN"C6"11;
"C7"
$PN"C7"5;
"C8"
$PN"C8"44;
"B5"
$PN"B5"2;
"B6"
$PN"B6"10;
"B7"
$PN"B7"2;
"B8"
$PN"B8"45;
"A5"
$PN"A5"58;
"A6"
$PN"A6"2;
"A7"
$PN"A7"4;
"A8"
$PN"A8"2;
END.
